# S9S_MB_2U (Grand Teton) — schematic netlist excerpt (pin names and nets, part order shuffled) for the footprints in the layout excerpt that follows; sources: Cadence DE-HDL packaged netlist, KiCad conversion of 03242023_DA0F0TMBIJ0_F0T_Motherboard_J_brd_V01_OCP.brd

R1352  Q_RES  100K 1% CHIP  pkg 0402LF  page 154 : A = RMII_OCP_BMC_RXD_1 ; B = GND
R2330  Q_RES  0 5% EMPTY  pkg 0402LF  page 306 : A = PWRGD_DSW_PWROK_R4 ; B = PWRGD_DSW_PWROK

(kicad_pcb
	(version 20260206)
	(generator "pcbnew")
	(generator_version "10.0")
	(general
		(thickness 1.6)
		(legacy_teardrops no)
	)
	(paper "A4")
	(title_block
		(title "03242023_DA0F0TMBIJ0_F0T_Motherboard_J_brd_V01_OCP.brd")
		(comment 1 "Grand Teton / footprints 3022-3023 of 6105")
	)
	(layers
		(0 "F.Cu" signal "TOP")
		(4 "In1.Cu" signal "GND")
		(6 "In2.Cu" signal "IN1")
		(8 "In3.Cu" signal "GND1")
		(10 "In4.Cu" signal "IN2")
		(12 "In5.Cu" signal "GND2")
		(14 "In6.Cu" signal "IN3")
		(16 "In7.Cu" signal "GND3")
		(18 "In8.Cu" signal "VCC")
		(20 "In9.Cu" signal "VCC1")
		(22 "In10.Cu" signal "GND4")
		(24 "In11.Cu" signal "IN4")
		(26 "In12.Cu" signal "GND5")
		(28 "In13.Cu" signal "IN5")
		(30 "In14.Cu" signal "GND6")
		(32 "In15.Cu" signal "IN6")
		(34 "In16.Cu" signal "GND7")
		(2 "B.Cu" signal "BOTTOM")
		(9 "F.Adhes" user "F.Adhesive")
		(11 "B.Adhes" user "B.Adhesive")
		(13 "F.Paste" user "Package Geometry/Pastemask Top")
		(15 "B.Paste" user "Package Geometry/Pastemask Bottom")
		(5 "F.SilkS" user "Ref Des/Silkscreen Top")
		(7 "B.SilkS" user "Ref Des/Silkscreen Bottom")
		(1 "F.Mask" user "Board Geometry/Soldermask Top")
		(3 "B.Mask" user "Board Geometry/Soldermask Bottom")
		(17 "Dwgs.User" user "User.Drawings")
		(19 "Cmts.User" user "User.Comments")
		(21 "Eco1.User" user "User.Eco1")
		(23 "Eco2.User" user "User.Eco2")
		(25 "Edge.Cuts" user "Board Geometry/Outline")
		(27 "Margin" user)
		(31 "F.CrtYd" user "Package Geometry/Place Bound Top")
		(29 "B.CrtYd" user "Package Geometry/Place Bound Bottom")
		(35 "F.Fab" user "Ref Des/Assembly Top")
		(33 "B.Fab" user "Ref Des/Assembly Bottom")
	)
	(footprint ""
		(layer "F.Cu")
		(at 196.708014 -78.42377 180)
		(property "Reference" "R1352"
			(at 0 0 180)
			(layer "F.SilkS")
			(hide yes)
			(effects
				(font
					(size 1.27 1.27)
				)
			)
		)
		(property "Value" ""
			(at 0 0 180)
			(layer "F.Fab")
			(effects
				(font
					(size 1.27 1.27)
				)
			)
		)
		(duplicate_pad_numbers_are_jumpers no)
		(fp_line
			(start 0.7874 0.4064)
			(end -0.7874 0.4064)
			(stroke
				(width 0.1524)
				(type default)
			)
			(layer "F.SilkS")
		)
		(fp_line
			(start 0.7874 -0.4064)
			(end 0.7874 0.4064)
			(stroke
				(width 0.1524)
				(type default)
			)
			(layer "F.SilkS")
		)
		(fp_line
			(start -0.7874 0.4064)
			(end -0.7874 -0.4064)
			(stroke
				(width 0.1524)
				(type default)
			)
			(layer "F.SilkS")
		)
		(fp_line
			(start -0.7874 -0.4064)
			(end 0.7874 -0.4064)
			(stroke
				(width 0.1524)
				(type default)
			)
			(layer "F.SilkS")
		)
		(fp_line
			(start 0.67945 0.3048)
			(end 0.120396 0.3048)
			(stroke
				(width 0.1)
				(type default)
			)
			(layer "F.Fab")
		)
		(fp_line
			(start 0.67945 -0.3048)
			(end 0.67945 0.3048)
			(stroke
				(width 0.1)
				(type default)
			)
			(layer "F.Fab")
		)
		(fp_line
			(start 0.12065 -0.2794)
			(end 0.12065 -0.3048)
			(stroke
				(width 0.1)
				(type default)
			)
			(layer "F.Fab")
		)
		(fp_line
			(start 0.12065 -0.3048)
			(end 0.67945 -0.3048)
			(stroke
				(width 0.1)
				(type default)
			)
			(layer "F.Fab")
		)
		(fp_line
			(start 0.120396 0.3048)
			(end 0.120396 0.2794)
			(stroke
				(width 0.1)
				(type default)
			)
			(layer "F.Fab")
		)
		(fp_line
			(start 0.120396 0.2794)
			(end -0.12065 0.2794)
			(stroke
				(width 0.1)
				(type default)
			)
			(layer "F.Fab")
		)
		(fp_line
			(start -0.12065 0.3048)
			(end -0.67945 0.3048)
			(stroke
				(width 0.1)
				(type default)
			)
			(layer "F.Fab")
		)
		(fp_line
			(start -0.12065 0.2794)
			(end -0.12065 0.3048)
			(stroke
				(width 0.1)
				(type default)
			)
			(layer "F.Fab")
		)
		(fp_line
			(start -0.12065 -0.2794)
			(end 0.12065 -0.2794)
			(stroke
				(width 0.1)
				(type default)
			)
			(layer "F.Fab")
		)
		(fp_line
			(start -0.12065 -0.305054)
			(end -0.12065 -0.2794)
			(stroke
				(width 0.1)
				(type default)
			)
			(layer "F.Fab")
		)
		(fp_line
			(start -0.67945 0.3048)
			(end -0.67945 -0.305054)
			(stroke
				(width 0.1)
				(type default)
			)
			(layer "F.Fab")
		)
		(fp_line
			(start -0.67945 -0.305054)
			(end -0.12065 -0.305054)
			(stroke
				(width 0.1)
				(type default)
			)
			(layer "F.Fab")
		)
		(pad "1" smd circle
			(at -0.40005 0 180)
			(size 0 0)
			(layers "F.Cu" "F.Mask" "F.Paste")
			(net "RMII_OCP_BMC_RXD_1")
		)
		(pad "2" smd circle
			(at 0.40005 0 180)
			(size 0 0)
			(layers "F.Cu" "F.Mask" "F.Paste")
			(net "GND")
		)
	)
	(footprint ""
		(layer "F.Cu")
		(at 220.100652 -103.330248)
		(property "Reference" "R2330"
			(at 0 0 0)
			(layer "F.SilkS")
			(hide yes)
			(effects
				(font
					(size 1.27 1.27)
				)
			)
		)
		(property "Value" ""
			(at 0 0 0)
			(layer "F.Fab")
			(effects
				(font
					(size 1.27 1.27)
				)
			)
		)
		(duplicate_pad_numbers_are_jumpers no)
		(fp_line
			(start -0.7874 -0.4064)
			(end 0.7874 -0.4064)
			(stroke
				(width 0.1524)
				(type default)
			)
			(layer "F.SilkS")
		)
		(fp_line
			(start -0.7874 0.4064)
			(end -0.7874 -0.4064)
			(stroke
				(width 0.1524)
				(type default)
			)
			(layer "F.SilkS")
		)
		(fp_line
			(start 0.7874 -0.4064)
			(end 0.7874 0.4064)
			(stroke
				(width 0.1524)
				(type default)
			)
			(layer "F.SilkS")
		)
		(fp_line
			(start 0.7874 0.4064)
			(end -0.7874 0.4064)
			(stroke
				(width 0.1524)
				(type default)
			)
			(layer "F.SilkS")
		)
		(fp_line
			(start -0.67945 -0.305054)
			(end -0.12065 -0.305054)
			(stroke
				(width 0.1)
				(type default)
			)
			(layer "F.Fab")
		)
		(fp_line
			(start -0.67945 0.3048)
			(end -0.67945 -0.305054)
			(stroke
				(width 0.1)
				(type default)
			)
			(layer "F.Fab")
		)
		(fp_line
			(start -0.12065 -0.305054)
			(end -0.12065 -0.2794)
			(stroke
				(width 0.1)
				(type default)
			)
			(layer "F.Fab")
		)
		(fp_line
			(start -0.12065 -0.2794)
			(end 0.12065 -0.2794)
			(stroke
				(width 0.1)
				(type default)
			)
			(layer "F.Fab")
		)
		(fp_line
			(start -0.12065 0.2794)
			(end -0.12065 0.3048)
			(stroke
				(width 0.1)
				(type default)
			)
			(layer "F.Fab")
		)
		(fp_line
			(start -0.12065 0.3048)
			(end -0.67945 0.3048)
			(stroke
				(width 0.1)
				(type default)
			)
			(layer "F.Fab")
		)
		(fp_line
			(start 0.120396 0.2794)
			(end -0.12065 0.2794)
			(stroke
				(width 0.1)
				(type default)
			)
			(layer "F.Fab")
		)
		(fp_line
			(start 0.120396 0.3048)
			(end 0.120396 0.2794)
			(stroke
				(width 0.1)
				(type default)
			)
			(layer "F.Fab")
		)
		(fp_line
			(start 0.12065 -0.3048)
			(end 0.67945 -0.3048)
			(stroke
				(width 0.1)
				(type default)
			)
			(layer "F.Fab")
		)
		(fp_line
			(start 0.12065 -0.2794)
			(end 0.12065 -0.3048)
			(stroke
				(width 0.1)
				(type default)
			)
			(layer "F.Fab")
		)
		(fp_line
			(start 0.67945 -0.3048)
			(end 0.67945 0.3048)
			(stroke
				(width 0.1)
				(type default)
			)
			(layer "F.Fab")
		)
		(fp_line
			(start 0.67945 0.3048)
			(end 0.120396 0.3048)
			(stroke
				(width 0.1)
				(type default)
			)
			(layer "F.Fab")
		)
		(pad "1" smd circle
			(at -0.40005 0)
			(size 0 0)
			(layers "F.Cu" "F.Mask" "F.Paste")
			(net "PWRGD_DSW_PWROK_R4")
		)
		(pad "2" smd circle
			(at 0.40005 0)
			(size 0 0)
			(layers "F.Cu" "F.Mask" "F.Paste")
			(net "PWRGD_DSW_PWROK")
		)
	)
)
